# T6G (Grand Teton) — schematic netlist excerpt (pin names and nets, part order shuffled) for the footprints in the layout excerpt that follows; sources: Cadence DE-HDL packaged netlist, KiCad conversion of 04192023_DAF0TMB3IC0_F0TG_MB_C_brd_V02_OCP.brd

PC514  Q_CAP  0.1UF 25V 10% EMPTY  pkg 0402  page 364 : A = P0V9_RETIMER_CPU1_VMON ; B = GND
R1141  Q_RES  27.4 1% CHIP  pkg 0402LF  page 133 : A = CLK_50M_NCSI_OCP_1 ; B = CLK_50M_NCSI_OCP_SFF

(kicad_pcb
	(version 20260206)
	(generator "pcbnew")
	(generator_version "10.0")
	(general
		(thickness 1.6)
		(legacy_teardrops no)
	)
	(paper "A4")
	(title_block
		(title "04192023_DAF0TMB3IC0_F0TG_MB_C_brd_V02_OCP.brd")
		(comment 1 "Grand Teton / footprints 3134-3135 of 8354")
	)
	(layers
		(0 "F.Cu" signal "TOP")
		(4 "In1.Cu" signal "GND")
		(6 "In2.Cu" signal "IN1")
		(8 "In3.Cu" signal "GND1")
		(10 "In4.Cu" signal "IN2")
		(12 "In5.Cu" signal "GND2")
		(14 "In6.Cu" signal "IN3")
		(16 "In7.Cu" signal "GND3")
		(18 "In8.Cu" signal "VCC")
		(20 "In9.Cu" signal "VCC1")
		(22 "In10.Cu" signal "GND4")
		(24 "In11.Cu" signal "IN4")
		(26 "In12.Cu" signal "GND5")
		(28 "In13.Cu" signal "IN5")
		(30 "In14.Cu" signal "GND6")
		(32 "In15.Cu" signal "IN6")
		(34 "In16.Cu" signal "GND7")
		(2 "B.Cu" signal "BOTTOM")
		(9 "F.Adhes" user "F.Adhesive")
		(11 "B.Adhes" user "B.Adhesive")
		(13 "F.Paste" user "Package Geometry/Pastemask Top")
		(15 "B.Paste" user "Package Geometry/Pastemask Bottom")
		(5 "F.SilkS" user "Ref Des/Silkscreen Top")
		(7 "B.SilkS" user "Ref Des/Silkscreen Bottom")
		(1 "F.Mask" user "Board Geometry/Soldermask Top")
		(3 "B.Mask" user "Board Geometry/Soldermask Bottom")
		(17 "Dwgs.User" user "User.Drawings")
		(19 "Cmts.User" user "User.Comments")
		(21 "Eco1.User" user "User.Eco1")
		(23 "Eco2.User" user "User.Eco2")
		(25 "Edge.Cuts" user "Board Geometry/Outline")
		(27 "Margin" user)
		(31 "F.CrtYd" user "Package Geometry/Place Bound Top")
		(29 "B.CrtYd" user "Package Geometry/Place Bound Bottom")
		(35 "F.Fab" user "Ref Des/Assembly Top")
		(33 "B.Fab" user "Ref Des/Assembly Bottom")
	)
	(footprint ""
		(layer "F.Cu")
		(at 211.21116 -16.343122 -90)
		(property "Reference" "R1141"
			(at 0 0 270)
			(layer "F.SilkS")
			(hide yes)
			(effects
				(font
					(size 1.27 1.27)
				)
			)
		)
		(property "Value" ""
			(at 0 0 270)
			(layer "F.Fab")
			(effects
				(font
					(size 1.27 1.27)
				)
			)
		)
		(duplicate_pad_numbers_are_jumpers no)
		(fp_line
			(start -0.7874 0.4064)
			(end -0.7874 -0.4064)
			(stroke
				(width 0.1524)
				(type default)
			)
			(layer "F.SilkS")
		)
		(fp_line
			(start 0.7874 0.4064)
			(end -0.7874 0.4064)
			(stroke
				(width 0.1524)
				(type default)
			)
			(layer "F.SilkS")
		)
		(fp_line
			(start -0.7874 -0.4064)
			(end 0.7874 -0.4064)
			(stroke
				(width 0.1524)
				(type default)
			)
			(layer "F.SilkS")
		)
		(fp_line
			(start 0.7874 -0.4064)
			(end 0.7874 0.4064)
			(stroke
				(width 0.1524)
				(type default)
			)
			(layer "F.SilkS")
		)
		(fp_line
			(start -0.67945 0.3048)
			(end -0.67945 -0.305054)
			(stroke
				(width 0.1)
				(type default)
			)
			(layer "F.Fab")
		)
		(fp_line
			(start -0.12065 0.3048)
			(end -0.67945 0.3048)
			(stroke
				(width 0.1)
				(type default)
			)
			(layer "F.Fab")
		)
		(fp_line
			(start 0.120396 0.3048)
			(end 0.120396 0.2794)
			(stroke
				(width 0.1)
				(type default)
			)
			(layer "F.Fab")
		)
		(fp_line
			(start 0.67945 0.3048)
			(end 0.120396 0.3048)
			(stroke
				(width 0.1)
				(type default)
			)
			(layer "F.Fab")
		)
		(fp_line
			(start -0.12065 0.2794)
			(end -0.12065 0.3048)
			(stroke
				(width 0.1)
				(type default)
			)
			(layer "F.Fab")
		)
		(fp_line
			(start 0.120396 0.2794)
			(end -0.12065 0.2794)
			(stroke
				(width 0.1)
				(type default)
			)
			(layer "F.Fab")
		)
		(fp_line
			(start -0.12065 -0.2794)
			(end 0.12065 -0.2794)
			(stroke
				(width 0.1)
				(type default)
			)
			(layer "F.Fab")
		)
		(fp_line
			(start 0.12065 -0.2794)
			(end 0.12065 -0.3048)
			(stroke
				(width 0.1)
				(type default)
			)
			(layer "F.Fab")
		)
		(fp_line
			(start 0.12065 -0.3048)
			(end 0.67945 -0.3048)
			(stroke
				(width 0.1)
				(type default)
			)
			(layer "F.Fab")
		)
		(fp_line
			(start 0.67945 -0.3048)
			(end 0.67945 0.3048)
			(stroke
				(width 0.1)
				(type default)
			)
			(layer "F.Fab")
		)
		(fp_line
			(start -0.67945 -0.305054)
			(end -0.12065 -0.305054)
			(stroke
				(width 0.1)
				(type default)
			)
			(layer "F.Fab")
		)
		(fp_line
			(start -0.12065 -0.305054)
			(end -0.12065 -0.2794)
			(stroke
				(width 0.1)
				(type default)
			)
			(layer "F.Fab")
		)
		(pad "1" smd circle
			(at -0.40005 0 270)
			(size 0 0)
			(layers "F.Cu" "F.Mask" "F.Paste")
			(net "CLK_50M_NCSI_OCP_1")
		)
		(pad "2" smd circle
			(at 0.40005 0 270)
			(size 0 0)
			(layers "F.Cu" "F.Mask" "F.Paste")
			(net "CLK_50M_NCSI_OCP_SFF")
		)
	)
	(footprint ""
		(layer "F.Cu")
		(at 10.066782 -409.675584 180)
		(property "Reference" "PC514"
			(at 0 0 180)
			(layer "F.SilkS")
			(hide yes)
			(effects
				(font
					(size 1.27 1.27)
				)
			)
		)
		(property "Value" ""
			(at 0 0 180)
			(layer "F.Fab")
			(effects
				(font
					(size 1.27 1.27)
				)
			)
		)
		(duplicate_pad_numbers_are_jumpers no)
		(fp_line
			(start 0.7874 0.4064)
			(end -0.7874 0.4064)
			(stroke
				(width 0.1524)
				(type default)
			)
			(layer "F.SilkS")
		)
		(fp_line
			(start 0.7874 -0.4064)
			(end 0.7874 0.4064)
			(stroke
				(width 0.1524)
				(type default)
			)
			(layer "F.SilkS")
		)
		(fp_line
			(start -0.7874 0.4064)
			(end -0.7874 -0.4064)
			(stroke
				(width 0.1524)
				(type default)
			)
			(layer "F.SilkS")
		)
		(fp_line
			(start -0.7874 -0.4064)
			(end 0.7874 -0.4064)
			(stroke
				(width 0.1524)
				(type default)
			)
			(layer "F.SilkS")
		)
		(fp_line
			(start 0.67945 0.3048)
			(end 0.120396 0.3048)
			(stroke
				(width 0.1)
				(type default)
			)
			(layer "F.Fab")
		)
		(fp_line
			(start 0.67945 -0.3048)
			(end 0.67945 0.3048)
			(stroke
				(width 0.1)
				(type default)
			)
			(layer "F.Fab")
		)
		(fp_line
			(start 0.12065 -0.2794)
			(end 0.12065 -0.3048)
			(stroke
				(width 0.1)
				(type default)
			)
			(layer "F.Fab")
		)
		(fp_line
			(start 0.12065 -0.3048)
			(end 0.67945 -0.3048)
			(stroke
				(width 0.1)
				(type default)
			)
			(layer "F.Fab")
		)
		(fp_line
			(start 0.120396 0.3048)
			(end 0.120396 0.2794)
			(stroke
				(width 0.1)
				(type default)
			)
			(layer "F.Fab")
		)
		(fp_line
			(start 0.120396 0.2794)
			(end -0.12065 0.2794)
			(stroke
				(width 0.1)
				(type default)
			)
			(layer "F.Fab")
		)
		(fp_line
			(start -0.12065 0.3048)
			(end -0.67945 0.3048)
			(stroke
				(width 0.1)
				(type default)
			)
			(layer "F.Fab")
		)
		(fp_line
			(start -0.12065 0.2794)
			(end -0.12065 0.3048)
			(stroke
				(width 0.1)
				(type default)
			)
			(layer "F.Fab")
		)
		(fp_line
			(start -0.12065 -0.2794)
			(end 0.12065 -0.2794)
			(stroke
				(width 0.1)
				(type default)
			)
			(layer "F.Fab")
		)
		(fp_line
			(start -0.12065 -0.305054)
			(end -0.12065 -0.2794)
			(stroke
				(width 0.1)
				(type default)
			)
			(layer "F.Fab")
		)
		(fp_line
			(start -0.67945 0.3048)
			(end -0.67945 -0.305054)
			(stroke
				(width 0.1)
				(type default)
			)
			(layer "F.Fab")
		)
		(fp_line
			(start -0.67945 -0.305054)
			(end -0.12065 -0.305054)
			(stroke
				(width 0.1)
				(type default)
			)
			(layer "F.Fab")
		)
		(pad "1" smd circle
			(at -0.40005 0 180)
			(size 0 0)
			(layers "F.Cu" "F.Mask" "F.Paste")
			(net "P0V9_RETIMER_CPU1_VMON")
		)
		(pad "2" smd circle
			(at 0.40005 0 180)
			(size 0 0)
			(layers "F.Cu" "F.Mask" "F.Paste")
			(net "GND")
		)
	)
)
